(kicad_pcb
	(version 20260206)
	(generator "pcbnew")
	(generator_version "10.0")
	(general
		(thickness 1.6)
		(legacy_teardrops no)
	)
	(paper "A4")
	(title_block
		(title "baseboard — 13948-1b.1110WZS1818.brd")
		(comment 1 "Honey Badger (Wiwynn) / footprints 1391-1398 of 2523")
	)
	(layers
		(0 "F.Cu" signal "TOP")
		(4 "In1.Cu" signal "L2GND")
		(6 "In2.Cu" signal "L3")
		(8 "In3.Cu" signal "L4VCC")
		(10 "In4.Cu" signal "L5VCC")
		(12 "In5.Cu" signal "L6")
		(14 "In6.Cu" signal "L7GND")
		(2 "B.Cu" signal "BOTTOM")
		(9 "F.Adhes" user "F.Adhesive")
		(11 "B.Adhes" user "B.Adhesive")
		(13 "F.Paste" user "Package Geometry/Pastemask Top")
		(15 "B.Paste" user "Package Geometry/Pastemask Bottom")
		(5 "F.SilkS" user "Ref Des/Silkscreen Top")
		(7 "B.SilkS" user "Ref Des/Silkscreen Bottom")
		(1 "F.Mask" user "Board Geometry/Soldermask Top")
		(3 "B.Mask" user "Board Geometry/Soldermask Bottom")
		(17 "Dwgs.User" user "User.Drawings")
		(19 "Cmts.User" user "User.Comments")
		(21 "Eco1.User" user "User.Eco1")
		(23 "Eco2.User" user "User.Eco2")
		(25 "Edge.Cuts" user "Board Geometry/Outline")
		(27 "Margin" user)
		(31 "F.CrtYd" user "Package Geometry/Place Bound Top")
		(29 "B.CrtYd" user "Package Geometry/Place Bound Bottom")
		(35 "F.Fab" user "Ref Des/Assembly Top")
		(33 "B.Fab" user "Ref Des/Assembly Bottom")
	)
	(footprint ""
		(layer "F.Cu")
		(at 347.345 -90.551)
		(property "Reference" "PG1"
			(at 0 0 0)
			(layer "F.SilkS")
			(hide yes)
			(effects
				(font
					(size 1.27 1.27)
				)
			)
		)
		(property "Value" "GAP-CLOSE-PWR-4-GP"
			(at -2.4638 -0.5461 0)
			(unlocked yes)
			(layer "F.Fab")
			(hide yes)
			(effects
				(font
					(size 1.016 1.016)
					(thickness 0.1524)
				)
			)
		)
		(property "Device Type" "GAP-CLOSE-PWR-4"
			(at -2.4638 -2.0701 0)
			(unlocked yes)
			(layer "F.Fab")
			(hide yes)
			(effects
				(font
					(size 1.016 1.016)
					(thickness 0.1524)
				)
			)
		)
		(duplicate_pad_numbers_are_jumpers no)
		(fp_rect
			(start -0.2794 0.254)
			(end 0.2794 -0.254)
			(stroke
				(width 0)
				(type default)
			)
			(fill no)
			(layer "F.CrtYd")
		)
		(fp_rect
			(start -0.2794 0.254)
			(end 0.2794 -0.254)
			(stroke
				(width 0)
				(type default)
			)
			(fill no)
			(layer "F.Fab")
		)
		(pad "1" smd rect
			(at -0.0635 0)
			(size 0.1778 0.254)
			(layers "F.Cu" "F.Mask" "F.Paste")
			(net "P5V_STBY")
		)
		(pad "2" smd rect
			(at 0.0635 0)
			(size 0.1778 0.254)
			(layers "F.Cu" "F.Mask" "F.Paste")
			(net "P5V_STBY_CC")
		)
	)
	(footprint ""
		(layer "F.Cu")
		(at 201.699876 -144.898872 90)
		(property "Reference" "SR762"
			(at 0 0 90)
			(layer "F.SilkS")
			(hide yes)
			(effects
				(font
					(size 1.27 1.27)
				)
			)
		)
		(property "Value" "4K7R2F-GP"
			(at 0.064008 -3.993896 90)
			(unlocked yes)
			(layer "F.Fab")
			(hide yes)
			(effects
				(font
					(size 1.016 1.016)
					(thickness 0.1524)
				)
			)
		)
		(property "Device Type" "R402H16"
			(at 0.064008 -5.517896 90)
			(unlocked yes)
			(layer "F.Fab")
			(hide yes)
			(effects
				(font
					(size 1.016 1.016)
					(thickness 0.1524)
				)
			)
		)
		(duplicate_pad_numbers_are_jumpers no)
		(fp_line
			(start 0.508 -0.9398)
			(end -0.508 -0.9398)
			(stroke
				(width 0.1524)
				(type default)
			)
			(layer "F.SilkS")
		)
		(fp_line
			(start -0.508 -0.9398)
			(end -0.508 0.9398)
			(stroke
				(width 0.1524)
				(type default)
			)
			(layer "F.SilkS")
		)
		(fp_rect
			(start -0.508 0.9398)
			(end 0.508 -0.9398)
			(stroke
				(width 0)
				(type default)
			)
			(fill no)
			(layer "F.CrtYd")
		)
		(fp_rect
			(start -0.508 0.9398)
			(end 0.508 -0.9398)
			(stroke
				(width 0)
				(type default)
			)
			(fill no)
			(layer "F.Fab")
		)
		(pad "1" smd custom
			(at 0 -0.4445 90)
			(size 0.1397 0.1397)
			(layers "F.Cu" "F.Mask" "F.Paste")
			(net "BMC_I2C_SDA_9")
			(options
				(clearance outline)
				(anchor circle)
			)
			(primitives
				(gr_poly
					(pts
						(arc
							(start -0.1778 -0.2794)
							(mid -0.249642 -0.249642)
							(end -0.2794 -0.1778)
						)
						(arc
							(start -0.2794 0.1778)
							(mid -0.249642 0.249642)
							(end -0.1778 0.2794)
						)
						(arc
							(start 0.1778 0.2794)
							(mid 0.249642 0.249642)
							(end 0.2794 0.1778)
						)
						(arc
							(start 0.2794 -0.1778)
							(mid 0.249642 -0.249642)
							(end 0.1778 -0.2794)
						)
					)
					(width 0)
					(fill yes)
				)
			)
		)
		(pad "2" smd custom
			(at 0 0.4445 90)
			(size 0.1397 0.1397)
			(layers "F.Cu" "F.Mask" "F.Paste")
			(net "P3V3_STBY")
			(options
				(clearance outline)
				(anchor circle)
			)
			(primitives
				(gr_poly
					(pts
						(arc
							(start -0.1778 -0.2794)
							(mid -0.249642 -0.249642)
							(end -0.2794 -0.1778)
						)
						(arc
							(start -0.2794 0.1778)
							(mid -0.249642 0.249642)
							(end -0.1778 0.2794)
						)
						(arc
							(start 0.1778 0.2794)
							(mid 0.249642 0.249642)
							(end 0.2794 0.1778)
						)
						(arc
							(start 0.2794 -0.1778)
							(mid 0.249642 -0.249642)
							(end 0.1778 -0.2794)
						)
					)
					(width 0)
					(fill yes)
				)
			)
		)
	)
	(footprint ""
		(layer "F.Cu")
		(at 90.786966 -63.119)
		(property "Reference" "SR672"
			(at 0 0 0)
			(layer "F.SilkS")
			(hide yes)
			(effects
				(font
					(size 1.27 1.27)
				)
			)
		)
		(property "Value" "4K7R2F-GP"
			(at 0.064008 -3.993896 0)
			(unlocked yes)
			(layer "F.Fab")
			(hide yes)
			(effects
				(font
					(size 1.016 1.016)
					(thickness 0.1524)
				)
			)
		)
		(property "Device Type" "R402H16"
			(at 0.064008 -5.517896 0)
			(unlocked yes)
			(layer "F.Fab")
			(hide yes)
			(effects
				(font
					(size 1.016 1.016)
					(thickness 0.1524)
				)
			)
		)
		(duplicate_pad_numbers_are_jumpers no)
		(fp_line
			(start -0.508 -0.9398)
			(end -0.508 0.9398)
			(stroke
				(width 0.1524)
				(type default)
			)
			(layer "F.SilkS")
		)
		(fp_line
			(start 0.508 -0.9398)
			(end -0.508 -0.9398)
			(stroke
				(width 0.1524)
				(type default)
			)
			(layer "F.SilkS")
		)
		(fp_rect
			(start -0.508 0.9398)
			(end 0.508 -0.9398)
			(stroke
				(width 0)
				(type default)
			)
			(fill no)
			(layer "F.CrtYd")
		)
		(fp_rect
			(start -0.508 0.9398)
			(end 0.508 -0.9398)
			(stroke
				(width 0)
				(type default)
			)
			(fill no)
			(layer "F.Fab")
		)
		(pad "1" smd custom
			(at 0 -0.4445)
			(size 0.1397 0.1397)
			(layers "F.Cu" "F.Mask" "F.Paste")
			(net "P1V8_C")
			(options
				(clearance outline)
				(anchor circle)
			)
			(primitives
				(gr_poly
					(pts
						(arc
							(start -0.1778 -0.2794)
							(mid -0.249642 -0.249642)
							(end -0.2794 -0.1778)
						)
						(arc
							(start -0.2794 0.1778)
							(mid -0.249642 0.249642)
							(end -0.1778 0.2794)
						)
						(arc
							(start 0.1778 0.2794)
							(mid 0.249642 0.249642)
							(end 0.2794 0.1778)
						)
						(arc
							(start 0.2794 -0.1778)
							(mid 0.249642 -0.249642)
							(end 0.1778 -0.2794)
						)
					)
					(width 0)
					(fill yes)
				)
			)
		)
		(pad "2" smd custom
			(at 0 0.4445)
			(size 0.1397 0.1397)
			(layers "F.Cu" "F.Mask" "F.Paste")
			(net "ICE1_TRST#")
			(options
				(clearance outline)
				(anchor circle)
			)
			(primitives
				(gr_poly
					(pts
						(arc
							(start -0.1778 -0.2794)
							(mid -0.249642 -0.249642)
							(end -0.2794 -0.1778)
						)
						(arc
							(start -0.2794 0.1778)
							(mid -0.249642 0.249642)
							(end -0.1778 0.2794)
						)
						(arc
							(start 0.1778 0.2794)
							(mid 0.249642 0.249642)
							(end 0.2794 0.1778)
						)
						(arc
							(start 0.2794 -0.1778)
							(mid 0.249642 -0.249642)
							(end 0.1778 -0.2794)
						)
					)
					(width 0)
					(fill yes)
				)
			)
		)
	)
	(footprint ""
		(layer "F.Cu")
		(at 342.138 -20.574 180)
		(property "Reference" "C255"
			(at 0 0 180)
			(layer "F.SilkS")
			(hide yes)
			(effects
				(font
					(size 1.27 1.27)
				)
			)
		)
		(property "Value" "SC1U6D3V3KX-2GP"
			(at 0 -2.8194 180)
			(unlocked yes)
			(layer "F.Fab")
			(hide yes)
			(effects
				(font
					(size 1.016 1.016)
					(thickness 0.1524)
				)
			)
		)
		(property "Device Type" "C603H36"
			(at 0 -4.3434 180)
			(unlocked yes)
			(layer "F.Fab")
			(hide yes)
			(effects
				(font
					(size 1.016 1.016)
					(thickness 0.1524)
				)
			)
		)
		(duplicate_pad_numbers_are_jumpers no)
		(fp_line
			(start 0.508 0)
			(end -0.508 0)
			(stroke
				(width 0.2032)
				(type default)
			)
			(layer "F.SilkS")
		)
		(fp_rect
			(start -0.5842 1.3335)
			(end 0.5842 -1.3335)
			(stroke
				(width 0)
				(type default)
			)
			(fill no)
			(layer "F.CrtYd")
		)
		(fp_rect
			(start -0.5842 1.3335)
			(end 0.5842 -1.3335)
			(stroke
				(width 0)
				(type default)
			)
			(fill no)
			(layer "F.Fab")
		)
		(pad "1" smd custom
			(at 0 -0.762 180)
			(size 0.2159 0.2159)
			(layers "F.Cu" "F.Mask" "F.Paste")
			(net "CPU_EXP_RST")
			(options
				(clearance outline)
				(anchor circle)
			)
			(primitives
				(gr_poly
					(pts
						(arc
							(start -0.3302 -0.4318)
							(mid -0.402042 -0.402042)
							(end -0.4318 -0.3302)
						)
						(arc
							(start -0.4318 0.3302)
							(mid -0.402042 0.402042)
							(end -0.3302 0.4318)
						)
						(arc
							(start 0.3302 0.4318)
							(mid 0.402042 0.402042)
							(end 0.4318 0.3302)
						)
						(arc
							(start 0.4318 -0.3302)
							(mid 0.402042 -0.402042)
							(end 0.3302 -0.4318)
						)
					)
					(width 0)
					(fill yes)
				)
			)
		)
		(pad "2" smd custom
			(at 0 0.762 180)
			(size 0.2159 0.2159)
			(layers "F.Cu" "F.Mask" "F.Paste")
			(net "GND")
			(options
				(clearance outline)
				(anchor circle)
			)
			(primitives
				(gr_poly
					(pts
						(arc
							(start -0.3302 -0.4318)
							(mid -0.402042 -0.402042)
							(end -0.4318 -0.3302)
						)
						(arc
							(start -0.4318 0.3302)
							(mid -0.402042 0.402042)
							(end -0.3302 0.4318)
						)
						(arc
							(start 0.3302 0.4318)
							(mid 0.402042 0.402042)
							(end 0.4318 0.3302)
						)
						(arc
							(start 0.4318 -0.3302)
							(mid 0.402042 -0.402042)
							(end 0.3302 -0.4318)
						)
					)
					(width 0)
					(fill yes)
				)
			)
		)
	)
	(footprint ""
		(layer "F.Cu")
		(at 97.663 -221.488)
		(property "Reference" "R639"
			(at 0 0 0)
			(layer "F.SilkS")
			(hide yes)
			(effects
				(font
					(size 1.27 1.27)
				)
			)
		)
		(property "Value" "4K7R2F-GP"
			(at 0.064008 -3.993896 0)
			(unlocked yes)
			(layer "F.Fab")
			(hide yes)
			(effects
				(font
					(size 1.016 1.016)
					(thickness 0.1524)
				)
			)
		)
		(property "Device Type" "R402H16"
			(at 0.064008 -5.517896 0)
			(unlocked yes)
			(layer "F.Fab")
			(hide yes)
			(effects
				(font
					(size 1.016 1.016)
					(thickness 0.1524)
				)
			)
		)
		(duplicate_pad_numbers_are_jumpers no)
		(fp_line
			(start -0.508 -0.9398)
			(end -0.508 0.9398)
			(stroke
				(width 0.1524)
				(type default)
			)
			(layer "F.SilkS")
		)
		(fp_line
			(start 0.508 -0.9398)
			(end -0.508 -0.9398)
			(stroke
				(width 0.1524)
				(type default)
			)
			(layer "F.SilkS")
		)
		(fp_rect
			(start -0.508 0.9398)
			(end 0.508 -0.9398)
			(stroke
				(width 0)
				(type default)
			)
			(fill no)
			(layer "F.CrtYd")
		)
		(fp_rect
			(start -0.508 0.9398)
			(end 0.508 -0.9398)
			(stroke
				(width 0)
				(type default)
			)
			(fill no)
			(layer "F.Fab")
		)
		(pad "1" smd custom
			(at 0 -0.4445)
			(size 0.1397 0.1397)
			(layers "F.Cu" "F.Mask" "F.Paste")
			(net "IO_EXP_HDD_FAULT_A0")
			(options
				(clearance outline)
				(anchor circle)
			)
			(primitives
				(gr_poly
					(pts
						(arc
							(start -0.1778 -0.2794)
							(mid -0.249642 -0.249642)
							(end -0.2794 -0.1778)
						)
						(arc
							(start -0.2794 0.1778)
							(mid -0.249642 0.249642)
							(end -0.1778 0.2794)
						)
						(arc
							(start 0.1778 0.2794)
							(mid 0.249642 0.249642)
							(end 0.2794 0.1778)
						)
						(arc
							(start 0.2794 -0.1778)
							(mid 0.249642 -0.249642)
							(end 0.1778 -0.2794)
						)
					)
					(width 0)
					(fill yes)
				)
			)
		)
		(pad "2" smd custom
			(at 0 0.4445)
			(size 0.1397 0.1397)
			(layers "F.Cu" "F.Mask" "F.Paste")
			(net "GND")
			(options
				(clearance outline)
				(anchor circle)
			)
			(primitives
				(gr_poly
					(pts
						(arc
							(start -0.1778 -0.2794)
							(mid -0.249642 -0.249642)
							(end -0.2794 -0.1778)
						)
						(arc
							(start -0.2794 0.1778)
							(mid -0.249642 0.249642)
							(end -0.1778 0.2794)
						)
						(arc
							(start 0.1778 0.2794)
							(mid 0.249642 0.249642)
							(end 0.2794 0.1778)
						)
						(arc
							(start 0.2794 -0.1778)
							(mid 0.249642 -0.249642)
							(end 0.1778 -0.2794)
						)
					)
					(width 0)
					(fill yes)
				)
			)
		)
	)
	(footprint ""
		(layer "F.Cu")
		(at 81.388966 -67.564 180)
		(property "Reference" "SC985"
			(at 0 0 180)
			(layer "F.SilkS")
			(hide yes)
			(effects
				(font
					(size 1.27 1.27)
				)
			)
		)
		(property "Value" "SCD1U16V2KX-3GP"
			(at 1.1811 -2.7051 180)
			(unlocked yes)
			(layer "F.Fab")
			(hide yes)
			(effects
				(font
					(size 1.016 1.016)
					(thickness 0.1524)
				)
			)
		)
		(property "Device Type" "C402H22"
			(at 1.1811 -4.2291 180)
			(unlocked yes)
			(layer "F.Fab")
			(hide yes)
			(effects
				(font
					(size 1.016 1.016)
					(thickness 0.1524)
				)
			)
		)
		(duplicate_pad_numbers_are_jumpers no)
		(fp_rect
			(start -0.4318 0.9525)
			(end 0.4318 -0.9525)
			(stroke
				(width 0)
				(type default)
			)
			(fill no)
			(layer "F.CrtYd")
		)
		(fp_rect
			(start -0.4318 0.9525)
			(end 0.4318 -0.9525)
			(stroke
				(width 0)
				(type default)
			)
			(fill no)
			(layer "F.Fab")
		)
		(pad "1" smd custom
			(at 0 -0.4445 180)
			(size 0.1524 0.1524)
			(layers "F.Cu" "F.Mask" "F.Paste")
			(net "P1V8_C")
			(options
				(clearance outline)
				(anchor circle)
			)
			(primitives
				(gr_poly
					(pts
						(arc
							(start 0.3048 -0.2032)
							(mid 0.275042 -0.275042)
							(end 0.2032 -0.3048)
						)
						(arc
							(start -0.2032 -0.3048)
							(mid -0.275042 -0.275042)
							(end -0.3048 -0.2032)
						)
						(arc
							(start -0.3048 0.2032)
							(mid -0.275042 0.275042)
							(end -0.2032 0.3048)
						)
						(arc
							(start 0.2032 0.3048)
							(mid 0.275042 0.275042)
							(end 0.3048 0.2032)
						)
					)
					(width 0)
					(fill yes)
				)
			)
		)
		(pad "2" smd custom
			(at 0 0.4445 180)
			(size 0.1524 0.1524)
			(layers "F.Cu" "F.Mask" "F.Paste")
			(net "GND")
			(options
				(clearance outline)
				(anchor circle)
			)
			(primitives
				(gr_poly
					(pts
						(arc
							(start 0.3048 -0.2032)
							(mid 0.275042 -0.275042)
							(end 0.2032 -0.3048)
						)
						(arc
							(start -0.2032 -0.3048)
							(mid -0.275042 -0.275042)
							(end -0.3048 -0.2032)
						)
						(arc
							(start -0.3048 0.2032)
							(mid -0.275042 0.275042)
							(end -0.2032 0.3048)
						)
						(arc
							(start 0.2032 0.3048)
							(mid 0.275042 0.275042)
							(end 0.3048 0.2032)
						)
					)
					(width 0)
					(fill yes)
				)
			)
		)
	)
	(footprint ""
		(layer "F.Cu")
		(at 336.169 -110.49)
		(property "Reference" "PR17"
			(at 0 0 0)
			(layer "F.SilkS")
			(hide yes)
			(effects
				(font
					(size 1.27 1.27)
				)
			)
		)
		(property "Value" "2K05R2F-GP"
			(at 0.064008 -3.993896 0)
			(unlocked yes)
			(layer "F.Fab")
			(hide yes)
			(effects
				(font
					(size 1.016 1.016)
					(thickness 0.1524)
				)
			)
		)
		(property "Device Type" "R402H16"
			(at 0.064008 -5.517896 0)
			(unlocked yes)
			(layer "F.Fab")
			(hide yes)
			(effects
				(font
					(size 1.016 1.016)
					(thickness 0.1524)
				)
			)
		)
		(duplicate_pad_numbers_are_jumpers no)
		(fp_line
			(start -0.508 -0.9398)
			(end -0.508 0.9398)
			(stroke
				(width 0.1524)
				(type default)
			)
			(layer "F.SilkS")
		)
		(fp_line
			(start 0.508 -0.9398)
			(end -0.508 -0.9398)
			(stroke
				(width 0.1524)
				(type default)
			)
			(layer "F.SilkS")
		)
		(fp_rect
			(start -0.508 0.9398)
			(end 0.508 -0.9398)
			(stroke
				(width 0)
				(type default)
			)
			(fill no)
			(layer "F.CrtYd")
		)
		(fp_rect
			(start -0.508 0.9398)
			(end 0.508 -0.9398)
			(stroke
				(width 0)
				(type default)
			)
			(fill no)
			(layer "F.Fab")
		)
		(pad "1" smd custom
			(at 0 -0.4445)
			(size 0.1397 0.1397)
			(layers "F.Cu" "F.Mask" "F.Paste")
			(net "P5V_STBY_EN_R")
			(options
				(clearance outline)
				(anchor circle)
			)
			(primitives
				(gr_poly
					(pts
						(arc
							(start -0.1778 -0.2794)
							(mid -0.249642 -0.249642)
							(end -0.2794 -0.1778)
						)
						(arc
							(start -0.2794 0.1778)
							(mid -0.249642 0.249642)
							(end -0.1778 0.2794)
						)
						(arc
							(start 0.1778 0.2794)
							(mid 0.249642 0.249642)
							(end 0.2794 0.1778)
						)
						(arc
							(start 0.2794 -0.1778)
							(mid 0.249642 -0.249642)
							(end 0.1778 -0.2794)
						)
					)
					(width 0)
					(fill yes)
				)
			)
		)
		(pad "2" smd custom
			(at 0 0.4445)
			(size 0.1397 0.1397)
			(layers "F.Cu" "F.Mask" "F.Paste")
			(net "GND")
			(options
				(clearance outline)
				(anchor circle)
			)
			(primitives
				(gr_poly
					(pts
						(arc
							(start -0.1778 -0.2794)
							(mid -0.249642 -0.249642)
							(end -0.2794 -0.1778)
						)
						(arc
							(start -0.2794 0.1778)
							(mid -0.249642 0.249642)
							(end -0.1778 0.2794)
						)
						(arc
							(start 0.1778 0.2794)
							(mid 0.249642 0.249642)
							(end 0.2794 0.1778)
						)
						(arc
							(start 0.2794 -0.1778)
							(mid 0.249642 -0.249642)
							(end 0.1778 -0.2794)
						)
					)
					(width 0)
					(fill yes)
				)
			)
		)
	)
	(footprint ""
		(layer "F.Cu")
		(at 95.504 -221.361)
		(property "Reference" "SR312"
			(at 0 0 0)
			(layer "F.SilkS")
			(hide yes)
			(effects
				(font
					(size 1.27 1.27)
				)
			)
		)
		(property "Value" "0R2J-2-GP"
			(at 0.064008 -3.993896 0)
			(unlocked yes)
			(layer "F.Fab")
			(hide yes)
			(effects
				(font
					(size 1.016 1.016)
					(thickness 0.1524)
				)
			)
		)
		(property "Device Type" "R402H16"
			(at 0.064008 -5.517896 0)
			(unlocked yes)
			(layer "F.Fab")
			(hide yes)
			(effects
				(font
					(size 1.016 1.016)
					(thickness 0.1524)
				)
			)
		)
		(duplicate_pad_numbers_are_jumpers no)
		(fp_line
			(start -0.508 -0.9398)
			(end -0.508 0.9398)
			(stroke
				(width 0.1524)
				(type default)
			)
			(layer "F.SilkS")
		)
		(fp_line
			(start 0.508 -0.9398)
			(end -0.508 -0.9398)
			(stroke
				(width 0.1524)
				(type default)
			)
			(layer "F.SilkS")
		)
		(fp_rect
			(start -0.508 0.9398)
			(end 0.508 -0.9398)
			(stroke
				(width 0)
				(type default)
			)
			(fill no)
			(layer "F.CrtYd")
		)
		(fp_rect
			(start -0.508 0.9398)
			(end 0.508 -0.9398)
			(stroke
				(width 0)
				(type default)
			)
			(fill no)
			(layer "F.Fab")
		)
		(pad "1" smd custom
			(at 0 -0.4445)
			(size 0.1397 0.1397)
			(layers "F.Cu" "F.Mask" "F.Paste")
			(net "FAULT_SCL")
			(options
				(clearance outline)
				(anchor circle)
			)
			(primitives
				(gr_poly
					(pts
						(arc
							(start -0.1778 -0.2794)
							(mid -0.249642 -0.249642)
							(end -0.2794 -0.1778)
						)
						(arc
							(start -0.2794 0.1778)
							(mid -0.249642 0.249642)
							(end -0.1778 0.2794)
						)
						(arc
							(start 0.1778 0.2794)
							(mid 0.249642 0.249642)
							(end 0.2794 0.1778)
						)
						(arc
							(start 0.2794 -0.1778)
							(mid 0.249642 -0.249642)
							(end 0.1778 -0.2794)
						)
					)
					(width 0)
					(fill yes)
				)
			)
		)
		(pad "2" smd custom
			(at 0 0.4445)
			(size 0.1397 0.1397)
			(layers "F.Cu" "F.Mask" "F.Paste")
			(net "BMC_I2C_SCL_10")
			(options
				(clearance outline)
				(anchor circle)
			)
			(primitives
				(gr_poly
					(pts
						(arc
							(start -0.1778 -0.2794)
							(mid -0.249642 -0.249642)
							(end -0.2794 -0.1778)
						)
						(arc
							(start -0.2794 0.1778)
							(mid -0.249642 0.249642)
							(end -0.1778 0.2794)
						)
						(arc
							(start 0.1778 0.2794)
							(mid 0.249642 0.249642)
							(end 0.2794 0.1778)
						)
						(arc
							(start 0.2794 -0.1778)
							(mid 0.249642 -0.249642)
							(end 0.1778 -0.2794)
						)
					)
					(width 0)
					(fill yes)
				)
			)
		)
	)
)
